# SCM (Grand Teton) — schematic netlist excerpt (pin names and nets, part order shuffled) for the footprints in the layout excerpt that follows; sources: Cadence DE-HDL packaged netlist, KiCad conversion of 12092022_DA0F0TMDCD0_F0T_Management_Board_D_brd_V3_OCP.brd

R432  Q_RES  0 5% CHIP  pkg 0402LF  page 35 : A = FM_PWR_R_BTN ; B = FM_PWR_BTN
C285  Q_CAP  0.01UF 50V 10% EMPTY  pkg C0402  page 41 : A = VCCIO2 ; B = GND

(kicad_pcb
	(version 20260206)
	(generator "pcbnew")
	(generator_version "10.0")
	(general
		(thickness 1.6)
		(legacy_teardrops no)
	)
	(paper "A4")
	(title_block
		(title "12092022_DA0F0TMDCD0_F0T_Management_Board_D_brd_V3_OCP.brd")
		(comment 1 "Grand Teton / footprints 1413-1414 of 1440")
	)
	(layers
		(0 "F.Cu" signal "TOP")
		(4 "In1.Cu" signal "GND")
		(6 "In2.Cu" signal "IN1")
		(8 "In3.Cu" signal "GND1")
		(10 "In4.Cu" signal "IN2")
		(12 "In5.Cu" signal "VCC")
		(14 "In6.Cu" signal "VCC1")
		(16 "In7.Cu" signal "IN3")
		(18 "In8.Cu" signal "GND2")
		(20 "In9.Cu" signal "IN4")
		(22 "In10.Cu" signal "GND3")
		(2 "B.Cu" signal "BOTTOM")
		(9 "F.Adhes" user "F.Adhesive")
		(11 "B.Adhes" user "B.Adhesive")
		(13 "F.Paste" user "Package Geometry/Pastemask Top")
		(15 "B.Paste" user "Package Geometry/Pastemask Bottom")
		(5 "F.SilkS" user "Ref Des/Silkscreen Top")
		(7 "B.SilkS" user "Ref Des/Silkscreen Bottom")
		(1 "F.Mask" user "Board Geometry/Soldermask Top")
		(3 "B.Mask" user "Board Geometry/Soldermask Bottom")
		(17 "Dwgs.User" user "User.Drawings")
		(19 "Cmts.User" user "User.Comments")
		(21 "Eco1.User" user "User.Eco1")
		(23 "Eco2.User" user "User.Eco2")
		(25 "Edge.Cuts" user "Board Geometry/Outline")
		(27 "Margin" user)
		(31 "F.CrtYd" user "Package Geometry/Place Bound Top")
		(29 "B.CrtYd" user "Package Geometry/Place Bound Bottom")
		(35 "F.Fab" user "Ref Des/Assembly Top")
		(33 "B.Fab" user "Ref Des/Assembly Bottom")
	)
	(footprint ""
		(layer "B.Cu")
		(at 22.65934 -95.187008 90)
		(property "Reference" "C285"
			(at 0 0 90)
			(layer "B.SilkS")
			(hide yes)
			(effects
				(font
					(size 1.27 1.27)
				)
				(justify mirror)
			)
		)
		(property "Value" ""
			(at 0 0 90)
			(layer "B.Fab")
			(effects
				(font
					(size 1.27 1.27)
				)
				(justify mirror)
			)
		)
		(duplicate_pad_numbers_are_jumpers no)
		(fp_line
			(start 0.69215 -0.2921)
			(end -0.69215 -0.2921)
			(stroke
				(width 0.1524)
				(type default)
			)
			(layer "B.SilkS")
		)
		(fp_line
			(start -0.69215 -0.2921)
			(end -0.69215 0.2921)
			(stroke
				(width 0.1524)
				(type default)
			)
			(layer "B.SilkS")
		)
		(fp_line
			(start 0.69215 0.2921)
			(end 0.69215 -0.2921)
			(stroke
				(width 0.1524)
				(type default)
			)
			(layer "B.SilkS")
		)
		(fp_line
			(start -0.69215 0.2921)
			(end 0.69215 0.2921)
			(stroke
				(width 0.1524)
				(type default)
			)
			(layer "B.SilkS")
		)
		(fp_line
			(start 0.51435 -0.2794)
			(end -0.51435 -0.2794)
			(stroke
				(width 0.1)
				(type default)
			)
			(layer "B.Fab")
		)
		(fp_line
			(start -0.51435 -0.2794)
			(end -0.51435 0.2794)
			(stroke
				(width 0.1)
				(type default)
			)
			(layer "B.Fab")
		)
		(fp_line
			(start 0.51435 0.2794)
			(end 0.51435 -0.2794)
			(stroke
				(width 0.1)
				(type default)
			)
			(layer "B.Fab")
		)
		(fp_line
			(start -0.51435 0.2794)
			(end 0.51435 0.2794)
			(stroke
				(width 0.1)
				(type default)
			)
			(layer "B.Fab")
		)
		(pad "1" smd circle
			(at 0.40005 0 270)
			(size 0 0)
			(layers "B.Cu" "B.Mask" "B.Paste")
			(net "VCCIO2")
		)
		(pad "2" smd circle
			(at -0.40005 0 270)
			(size 0 0)
			(layers "B.Cu" "B.Mask" "B.Paste")
			(net "GND")
		)
		(zone
			(layer "B.Cu")
			(hatch none 0.5)
			(connect_pads
				(clearance 0)
			)
			(min_thickness 0.25)
			(keepout
				(tracks not_allowed)
				(vias allowed)
				(pads allowed)
				(copperpour not_allowed)
				(footprints allowed)
			)
			(placement
				(enabled no)
				(sheetname "")
			)
			(fill
				(thermal_gap 0.5)
				(thermal_bridge_width 0.5)
				(island_removal_mode 0)
			)
			(polygon
				(pts
					(xy 22.74697 -95.377508) (xy 22.805136 -95.286068) (xy 22.805136 -95.086678) (xy 22.74697 -94.996508)
					(xy 22.57171 -94.996508) (xy 22.51329 -95.086678) (xy 22.51329 -95.286068) (xy 22.571456 -95.377508)
				)
			)
		)
	)
	(footprint ""
		(layer "B.Cu")
		(at 12.319 -96.52)
		(property "Reference" "R432"
			(at 0 0 0)
			(layer "B.SilkS")
			(hide yes)
			(effects
				(font
					(size 1.27 1.27)
				)
				(justify mirror)
			)
		)
		(property "Value" ""
			(at 0 0 0)
			(layer "B.Fab")
			(effects
				(font
					(size 1.27 1.27)
				)
				(justify mirror)
			)
		)
		(duplicate_pad_numbers_are_jumpers no)
		(fp_line
			(start -0.7874 -0.4064)
			(end -0.7874 0.4064)
			(stroke
				(width 0.1524)
				(type default)
			)
			(layer "B.SilkS")
		)
		(fp_line
			(start -0.7874 0.4064)
			(end 0.7874 0.4064)
			(stroke
				(width 0.1524)
				(type default)
			)
			(layer "B.SilkS")
		)
		(fp_line
			(start 0.7874 -0.4064)
			(end -0.7874 -0.4064)
			(stroke
				(width 0.1524)
				(type default)
			)
			(layer "B.SilkS")
		)
		(fp_line
			(start 0.7874 0.4064)
			(end 0.7874 -0.4064)
			(stroke
				(width 0.1524)
				(type default)
			)
			(layer "B.SilkS")
		)
		(fp_line
			(start -0.67945 -0.3048)
			(end -0.67945 0.3048)
			(stroke
				(width 0.1)
				(type default)
			)
			(layer "B.Fab")
		)
		(fp_line
			(start -0.67945 0.3048)
			(end -0.120396 0.3048)
			(stroke
				(width 0.1)
				(type default)
			)
			(layer "B.Fab")
		)
		(fp_line
			(start -0.12065 -0.3048)
			(end -0.67945 -0.3048)
			(stroke
				(width 0.1)
				(type default)
			)
			(layer "B.Fab")
		)
		(fp_line
			(start -0.12065 -0.2794)
			(end -0.12065 -0.3048)
			(stroke
				(width 0.1)
				(type default)
			)
			(layer "B.Fab")
		)
		(fp_line
			(start -0.120396 0.2794)
			(end 0.12065 0.2794)
			(stroke
				(width 0.1)
				(type default)
			)
			(layer "B.Fab")
		)
		(fp_line
			(start -0.120396 0.3048)
			(end -0.120396 0.2794)
			(stroke
				(width 0.1)
				(type default)
			)
			(layer "B.Fab")
		)
		(fp_line
			(start 0.12065 -0.305054)
			(end 0.12065 -0.2794)
			(stroke
				(width 0.1)
				(type default)
			)
			(layer "B.Fab")
		)
		(fp_line
			(start 0.12065 -0.2794)
			(end -0.12065 -0.2794)
			(stroke
				(width 0.1)
				(type default)
			)
			(layer "B.Fab")
		)
		(fp_line
			(start 0.12065 0.2794)
			(end 0.12065 0.3048)
			(stroke
				(width 0.1)
				(type default)
			)
			(layer "B.Fab")
		)
		(fp_line
			(start 0.12065 0.3048)
			(end 0.67945 0.3048)
			(stroke
				(width 0.1)
				(type default)
			)
			(layer "B.Fab")
		)
		(fp_line
			(start 0.67945 -0.305054)
			(end 0.12065 -0.305054)
			(stroke
				(width 0.1)
				(type default)
			)
			(layer "B.Fab")
		)
		(fp_line
			(start 0.67945 0.3048)
			(end 0.67945 -0.305054)
			(stroke
				(width 0.1)
				(type default)
			)
			(layer "B.Fab")
		)
		(pad "1" smd circle
			(at 0.40005 0 180)
			(size 0 0)
			(layers "B.Cu" "B.Mask" "B.Paste")
			(net "FM_PWR_R_BTN")
		)
		(pad "2" smd circle
			(at -0.40005 0 180)
			(size 0 0)
			(layers "B.Cu" "B.Mask" "B.Paste")
			(net "FM_PWR_BTN")
		)
	)
)
